# T6G (Grand Teton) — schematic netlist excerpt (pin names and nets, part order shuffled) for the footprints in the layout excerpt that follows; sources: Cadence DE-HDL packaged netlist, KiCad conversion of 04192023_DAF0TMB3IC0_F0TG_MB_C_brd_V02_OCP.brd

R3826  Q_RES  100K 1% EMPTY  pkg 0402LF  page 140 : A = P3V3_AUX ; B = OCP_V3_2_P3V3_PWRGD
H2  HOLE  EMPTY  pkg TH  page 230 : \1\ = GND
R6154  Q_RES  0 5% CHIP  pkg 0201LF  page 113 : A = P2E_MB_BMC_TX_C_DP<0> ; B = P2E_MB_BMC_TX_C_R2_DP<0>
R477  Q_RES  33 5% CHIP  pkg 0402LF  page 172 : A = CPU0_XTRIG_L7 ; B = HDT_CPU0_XTRIG_L7

(kicad_pcb
	(version 20260206)
	(generator "pcbnew")
	(generator_version "10.0")
	(general
		(thickness 1.6)
		(legacy_teardrops no)
	)
	(paper "A4")
	(title_block
		(title "04192023_DAF0TMB3IC0_F0TG_MB_C_brd_V02_OCP.brd")
		(comment 1 "Grand Teton / footprints 2584-2587 of 8354")
	)
	(layers
		(0 "F.Cu" signal "TOP")
		(4 "In1.Cu" signal "GND")
		(6 "In2.Cu" signal "IN1")
		(8 "In3.Cu" signal "GND1")
		(10 "In4.Cu" signal "IN2")
		(12 "In5.Cu" signal "GND2")
		(14 "In6.Cu" signal "IN3")
		(16 "In7.Cu" signal "GND3")
		(18 "In8.Cu" signal "VCC")
		(20 "In9.Cu" signal "VCC1")
		(22 "In10.Cu" signal "GND4")
		(24 "In11.Cu" signal "IN4")
		(26 "In12.Cu" signal "GND5")
		(28 "In13.Cu" signal "IN5")
		(30 "In14.Cu" signal "GND6")
		(32 "In15.Cu" signal "IN6")
		(34 "In16.Cu" signal "GND7")
		(2 "B.Cu" signal "BOTTOM")
		(9 "F.Adhes" user "F.Adhesive")
		(11 "B.Adhes" user "B.Adhesive")
		(13 "F.Paste" user "Package Geometry/Pastemask Top")
		(15 "B.Paste" user "Package Geometry/Pastemask Bottom")
		(5 "F.SilkS" user "Ref Des/Silkscreen Top")
		(7 "B.SilkS" user "Ref Des/Silkscreen Bottom")
		(1 "F.Mask" user "Board Geometry/Soldermask Top")
		(3 "B.Mask" user "Board Geometry/Soldermask Bottom")
		(17 "Dwgs.User" user "User.Drawings")
		(19 "Cmts.User" user "User.Comments")
		(21 "Eco1.User" user "User.Eco1")
		(23 "Eco2.User" user "User.Eco2")
		(25 "Edge.Cuts" user "Board Geometry/Outline")
		(27 "Margin" user)
		(31 "F.CrtYd" user "Package Geometry/Place Bound Top")
		(29 "B.CrtYd" user "Package Geometry/Place Bound Bottom")
		(35 "F.Fab" user "Ref Des/Assembly Top")
		(33 "B.Fab" user "Ref Des/Assembly Bottom")
	)
	(footprint ""
		(layer "F.Cu")
		(at 403.682962 -60.7695 180)
		(property "Reference" "R477"
			(at 0 0 180)
			(layer "F.SilkS")
			(hide yes)
			(effects
				(font
					(size 1.27 1.27)
				)
			)
		)
		(property "Value" ""
			(at 0 0 180)
			(layer "F.Fab")
			(effects
				(font
					(size 1.27 1.27)
				)
			)
		)
		(duplicate_pad_numbers_are_jumpers no)
		(fp_line
			(start 0.7874 0.4064)
			(end -0.7874 0.4064)
			(stroke
				(width 0.1524)
				(type default)
			)
			(layer "F.SilkS")
		)
		(fp_line
			(start 0.7874 -0.4064)
			(end 0.7874 0.4064)
			(stroke
				(width 0.1524)
				(type default)
			)
			(layer "F.SilkS")
		)
		(fp_line
			(start -0.7874 0.4064)
			(end -0.7874 -0.4064)
			(stroke
				(width 0.1524)
				(type default)
			)
			(layer "F.SilkS")
		)
		(fp_line
			(start -0.7874 -0.4064)
			(end 0.7874 -0.4064)
			(stroke
				(width 0.1524)
				(type default)
			)
			(layer "F.SilkS")
		)
		(fp_line
			(start 0.67945 0.3048)
			(end 0.120396 0.3048)
			(stroke
				(width 0.1)
				(type default)
			)
			(layer "F.Fab")
		)
		(fp_line
			(start 0.67945 -0.3048)
			(end 0.67945 0.3048)
			(stroke
				(width 0.1)
				(type default)
			)
			(layer "F.Fab")
		)
		(fp_line
			(start 0.12065 -0.2794)
			(end 0.12065 -0.3048)
			(stroke
				(width 0.1)
				(type default)
			)
			(layer "F.Fab")
		)
		(fp_line
			(start 0.12065 -0.3048)
			(end 0.67945 -0.3048)
			(stroke
				(width 0.1)
				(type default)
			)
			(layer "F.Fab")
		)
		(fp_line
			(start 0.120396 0.3048)
			(end 0.120396 0.2794)
			(stroke
				(width 0.1)
				(type default)
			)
			(layer "F.Fab")
		)
		(fp_line
			(start 0.120396 0.2794)
			(end -0.12065 0.2794)
			(stroke
				(width 0.1)
				(type default)
			)
			(layer "F.Fab")
		)
		(fp_line
			(start -0.12065 0.3048)
			(end -0.67945 0.3048)
			(stroke
				(width 0.1)
				(type default)
			)
			(layer "F.Fab")
		)
		(fp_line
			(start -0.12065 0.2794)
			(end -0.12065 0.3048)
			(stroke
				(width 0.1)
				(type default)
			)
			(layer "F.Fab")
		)
		(fp_line
			(start -0.12065 -0.2794)
			(end 0.12065 -0.2794)
			(stroke
				(width 0.1)
				(type default)
			)
			(layer "F.Fab")
		)
		(fp_line
			(start -0.12065 -0.305054)
			(end -0.12065 -0.2794)
			(stroke
				(width 0.1)
				(type default)
			)
			(layer "F.Fab")
		)
		(fp_line
			(start -0.67945 0.3048)
			(end -0.67945 -0.305054)
			(stroke
				(width 0.1)
				(type default)
			)
			(layer "F.Fab")
		)
		(fp_line
			(start -0.67945 -0.305054)
			(end -0.12065 -0.305054)
			(stroke
				(width 0.1)
				(type default)
			)
			(layer "F.Fab")
		)
		(pad "1" smd circle
			(at -0.40005 0 180)
			(size 0 0)
			(layers "F.Cu" "F.Mask" "F.Paste")
			(net "CPU0_XTRIG_L7")
		)
		(pad "2" smd circle
			(at 0.40005 0 180)
			(size 0 0)
			(layers "F.Cu" "F.Mask" "F.Paste")
			(net "HDT_CPU0_XTRIG_L7")
		)
	)
	(footprint ""
		(layer "F.Cu")
		(at 39.842694 -422.06037)
		(property "Reference" "R6154"
			(at 0 0 0)
			(layer "F.SilkS")
			(hide yes)
			(effects
				(font
					(size 1.27 1.27)
				)
			)
		)
		(property "Value" ""
			(at 0 0 0)
			(layer "F.Fab")
			(effects
				(font
					(size 1.27 1.27)
				)
			)
		)
		(duplicate_pad_numbers_are_jumpers no)
		(fp_line
			(start -0.32512 -0.175006)
			(end 0.32512 -0.175006)
			(stroke
				(width 0.1)
				(type default)
			)
			(layer "F.Fab")
		)
		(fp_line
			(start -0.32512 0.175006)
			(end -0.32512 -0.175006)
			(stroke
				(width 0.1)
				(type default)
			)
			(layer "F.Fab")
		)
		(fp_line
			(start 0.32512 -0.175006)
			(end 0.32512 0.175006)
			(stroke
				(width 0.1)
				(type default)
			)
			(layer "F.Fab")
		)
		(fp_line
			(start 0.32512 0.175006)
			(end -0.32512 0.175006)
			(stroke
				(width 0.1)
				(type default)
			)
			(layer "F.Fab")
		)
		(pad "1" smd rect
			(at -0.2667 0)
			(size 0.3048 0.381)
			(layers "F.Cu" "F.Mask" "F.Paste")
			(net "P2E_MB_BMC_TX_C_DP<0>")
		)
		(pad "2" smd rect
			(at 0.2667 0 180)
			(size 0.3048 0.381)
			(layers "F.Cu" "F.Mask" "F.Paste")
			(net "P2E_MB_BMC_TX_C_R2_DP<0>")
		)
	)
	(footprint ""
		(layer "F.Cu")
		(at 87.54618 -58.21172 180)
		(property "Reference" "R3826"
			(at 0 0 180)
			(layer "F.SilkS")
			(hide yes)
			(effects
				(font
					(size 1.27 1.27)
				)
			)
		)
		(property "Value" ""
			(at 0 0 180)
			(layer "F.Fab")
			(effects
				(font
					(size 1.27 1.27)
				)
			)
		)
		(duplicate_pad_numbers_are_jumpers no)
		(fp_line
			(start 0.7874 0.4064)
			(end -0.7874 0.4064)
			(stroke
				(width 0.1524)
				(type default)
			)
			(layer "F.SilkS")
		)
		(fp_line
			(start 0.7874 -0.4064)
			(end 0.7874 0.4064)
			(stroke
				(width 0.1524)
				(type default)
			)
			(layer "F.SilkS")
		)
		(fp_line
			(start -0.7874 0.4064)
			(end -0.7874 -0.4064)
			(stroke
				(width 0.1524)
				(type default)
			)
			(layer "F.SilkS")
		)
		(fp_line
			(start -0.7874 -0.4064)
			(end 0.7874 -0.4064)
			(stroke
				(width 0.1524)
				(type default)
			)
			(layer "F.SilkS")
		)
		(fp_line
			(start 0.67945 0.3048)
			(end 0.120396 0.3048)
			(stroke
				(width 0.1)
				(type default)
			)
			(layer "F.Fab")
		)
		(fp_line
			(start 0.67945 -0.3048)
			(end 0.67945 0.3048)
			(stroke
				(width 0.1)
				(type default)
			)
			(layer "F.Fab")
		)
		(fp_line
			(start 0.12065 -0.2794)
			(end 0.12065 -0.3048)
			(stroke
				(width 0.1)
				(type default)
			)
			(layer "F.Fab")
		)
		(fp_line
			(start 0.12065 -0.3048)
			(end 0.67945 -0.3048)
			(stroke
				(width 0.1)
				(type default)
			)
			(layer "F.Fab")
		)
		(fp_line
			(start 0.120396 0.3048)
			(end 0.120396 0.2794)
			(stroke
				(width 0.1)
				(type default)
			)
			(layer "F.Fab")
		)
		(fp_line
			(start 0.120396 0.2794)
			(end -0.12065 0.2794)
			(stroke
				(width 0.1)
				(type default)
			)
			(layer "F.Fab")
		)
		(fp_line
			(start -0.12065 0.3048)
			(end -0.67945 0.3048)
			(stroke
				(width 0.1)
				(type default)
			)
			(layer "F.Fab")
		)
		(fp_line
			(start -0.12065 0.2794)
			(end -0.12065 0.3048)
			(stroke
				(width 0.1)
				(type default)
			)
			(layer "F.Fab")
		)
		(fp_line
			(start -0.12065 -0.2794)
			(end 0.12065 -0.2794)
			(stroke
				(width 0.1)
				(type default)
			)
			(layer "F.Fab")
		)
		(fp_line
			(start -0.12065 -0.305054)
			(end -0.12065 -0.2794)
			(stroke
				(width 0.1)
				(type default)
			)
			(layer "F.Fab")
		)
		(fp_line
			(start -0.67945 0.3048)
			(end -0.67945 -0.305054)
			(stroke
				(width 0.1)
				(type default)
			)
			(layer "F.Fab")
		)
		(fp_line
			(start -0.67945 -0.305054)
			(end -0.12065 -0.305054)
			(stroke
				(width 0.1)
				(type default)
			)
			(layer "F.Fab")
		)
		(pad "1" smd circle
			(at -0.40005 0 180)
			(size 0 0)
			(layers "F.Cu" "F.Mask" "F.Paste")
			(net "P3V3_AUX")
		)
		(pad "2" smd circle
			(at 0.40005 0 180)
			(size 0 0)
			(layers "F.Cu" "F.Mask" "F.Paste")
			(net "OCP_V3_2_P3V3_PWRGD")
		)
	)
	(footprint ""
		(layer "F.Cu")
		(at 463.439764 -399.030952)
		(property "Reference" "H2"
			(at -2.5146 -3.58013 0)
			(unlocked yes)
			(layer "F.SilkS")
			(effects
				(font
					(size 0.7874 0.5842)
					(thickness 0.1524)
				)
				(justify left)
			)
		)
		(property "Value" ""
			(at 0 0 0)
			(layer "F.Fab")
			(effects
				(font
					(size 1.27 1.27)
				)
			)
		)
		(duplicate_pad_numbers_are_jumpers no)
		(pad "1" thru_hole circle
			(at 0 0)
			(size 6.1976 6.1976)
			(drill 3.7338)
			(layers "*.Cu" "*.Mask")
			(remove_unused_layers no)
			(net "GND")
			(clearance -0.9779)
			(padstack
				(mode front_inner_back)
				(layer "Inner"
					(shape circle)
					(size 5.5372 5.5372)
					(clearance -0.6477)
				)
				(layer "B.Cu"
					(shape circle)
					(size 6.1976 6.1976)
					(clearance -0.9779)
				)
			)
		)
	)
)
